# BASEBOARD_FAB2 (Tioga Pass) — schematic netlist excerpt (pin names and nets, part order shuffled) for the footprints in the layout excerpt that follows; sources: Cadence DE-HDL packaged netlist, KiCad conversion of Wiwynn_Tioga_Pass_MB.brd

J8G1  SCONN200_H68296001  CONN  pkg SM  page 108
  IO1  = P12V
  IO2  = P12V
  IO3  = P12V
  IO4  = P12V
  IO5  = P12V
  IO6  = P12V
  IO7  = P12V
  IO8  = P12V
  IO9  = P12V
  IO10  = P12V
  IO11  = P12V
  IO12  = P12V
  IO13  = GND
  IO14  = GND
  IO15  = SMB_SLOTX24_STBY_LVC3_SDA_R2
  IO16  = IRQ_OOB_MGMT_RISER_ALERT_N
  IO17  = SMB_SLOTX24_STBY_LVC3_SCL_R2
  IO18  = FM_SLT_CFG1
  IO19  = FM_SLT_CFG0
  IO20  = FM_PWRBRK_SLOT_N
  IO21  = P3V3
  IO22  = P3V3
  IO23  = P3V3
  IO24  = P3V3
  IO25  = P3V3_STBY
  IO26  = GND
  IO27  = PU_PCH_TLS_ENABLE_STRAP
  IO28  = FM_PE_SLOTX24_WAKE_N
  IO29  = RST_PCIE_RISER1_PERST_R_N
  IO30  = SMB_HOST_STBY_LVC3_SDA_R5
  IO31  = GND
  IO32  = SMB_HOST_STBY_LVC3_SCL_R5
  IO33  = CLK_100M_PCH_SLOTX24_S5_DP
  IO34  = GND
  IO35  = CLK_100M_PCH_SLOTX24_S5_DN
  IO36  = CLK_100M_PCH_SLOTX24_S4_DP
  IO37  = GND
  IO38  = CLK_100M_PCH_SLOTX24_S4_DN
  IO39  = CLK_100M_PCH_SLOTX24_S0_DP
  IO40  = GND
  IO41  = CLK_100M_PCH_SLOTX24_S0_DN
  IO42  = CLK_100M_PCH_SLOTX24_S1_DP
  IO43  = GND
  IO44  = CLK_100M_PCH_SLOTX24_S1_DN
  IO45  = CLK_100M_PCH_SLOTX24_S3_DP
  IO46  = GND
  IO47  = CLK_100M_PCH_SLOTX24_S3_DN
  IO48  = CLK_100M_PCH_SLOTX24_S2_DP
  IO49  = GND
  IO50  = CLK_100M_PCH_SLOTX24_S2_DN
  IO51  = P3E_CPU0_PE1_PCH_CON_TXN<15>
  IO52  = GND
  IO53  = P3E_CPU0_PE1_PCH_CON_TXP<15>
  IO54  = P3E_CPU0_PE1_PCH_CON_RXN<15>
  IO55  = GND
  IO56  = P3E_CPU0_PE1_PCH_CON_RXP<15>
  IO57  = P3E_CPU0_PE1_PCH_CON_TXP<14>
  IO58  = GND
  IO59  = P3E_CPU0_PE1_PCH_CON_TXN<14>
  IO60  = P3E_CPU0_PE1_PCH_CON_RXN<14>
  IO61  = GND
  IO62  = P3E_CPU0_PE1_PCH_CON_RXP<14>
  IO63  = TP_SLOTX24_RSVD63
  IO64  = GND
  IO65  = GND
  IO66  = TP_SLOTX24_RSVD66
  IO67  = P3E_CPU0_PE1_PCH_CON_TXN<13>
  IO68  = GND
  IO69  = P3E_CPU0_PE1_PCH_CON_TXP<13>
  IO70  = P3E_CPU0_PE1_PCH_CON_RXN<13>
  IO71  = GND
  IO72  = P3E_CPU0_PE1_PCH_CON_RXP<13>
  IO73  = P3E_CPU0_PE1_PCH_CON_TXN<12>
  IO74  = GND
  IO75  = P3E_CPU0_PE1_PCH_CON_TXP<12>
  IO76  = P3E_CPU0_PE1_PCH_CON_RXN<12>
  IO77  = GND
  IO78  = P3E_CPU0_PE1_PCH_CON_RXP<12>
  IO79  = P3E_CPU0_PE1_PCH_CON_TXN<11>
  IO80  = GND
  IO81  = P3E_CPU0_PE1_PCH_CON_TXP<11>
  IO82  = P3E_CPU0_PE1_PCH_CON_RXN<11>
  IO83  = GND
  IO84  = P3E_CPU0_PE1_PCH_CON_RXP<11>
  IO85  = P3E_CPU0_PE1_PCH_CON_TXN<10>
  IO86  = GND
  IO87  = P3E_CPU0_PE1_PCH_CON_TXP<10>
  IO88  = P3E_CPU0_PE1_PCH_CON_RXN<10>
  IO89  = GND
  IO90  = P3E_CPU0_PE1_PCH_CON_RXP<10>
  IO91  = P3E_CPU0_PE1_PCH_CON_TXN<9>
  IO92  = GND
  IO93  = P3E_CPU0_PE1_PCH_CON_TXP<9>
  IO94  = P3E_CPU0_PE1_PCH_CON_RXN<9>
  IO95  = GND
  IO96  = P3E_CPU0_PE1_PCH_CON_RXP<9>
  IO97  = P3E_CPU0_PE1_PCH_CON_TXN<8>
  IO98  = GND
  IO99  = P3E_CPU0_PE1_PCH_CON_TXP<8>
  IO100  = P3E_CPU0_PE1_PCH_CON_RXN<8>
  IO101  = GND
  IO102  = P3E_CPU0_PE1_PCH_CON_RXP<8>
  IO103  = P3E_CPU0_PE1_SS_C_TXP<7>
  IO104  = GND
  IO105  = P3E_CPU0_PE1_SS_C_TXN<7>
  IO106  = P3E_CPU0_PE1_SS_R_RXN<7>
  IO107  = GND
  IO108  = P3E_CPU0_PE1_SS_R_RXP<7>
  IO109  = P3E_CPU0_PE1_SS_C_TXN<6>
  IO110  = GND
  IO111  = P3E_CPU0_PE1_SS_C_TXP<6>
  IO112  = P3E_CPU0_PE1_SS_R_RXN<6>
  IO113  = GND
  IO114  = P3E_CPU0_PE1_SS_R_RXP<6>
  IO115  = P3E_CPU0_PE1_SS_C_TXN<5>
  IO116  = GND
  IO117  = P3E_CPU0_PE1_SS_C_TXP<5>
  IO118  = P3E_CPU0_PE1_SS_R_RXN<5>
  IO119  = GND
  IO120  = P3E_CPU0_PE1_SS_R_RXP<5>
  IO121  = P3E_CPU0_PE1_SS_C_TXN<4>
  IO122  = GND
  IO123  = P3E_CPU0_PE1_SS_C_TXP<4>
  IO124  = P3E_CPU0_PE1_SS_R_RXN<4>
  IO125  = GND
  IO126  = P3E_CPU0_PE1_SS_R_RXP<4>
  IO127  = P3E_CPU0_PE1_SS_C_TXN<3>
  IO128  = GND
  IO129  = P3E_CPU0_PE1_SS_C_TXP<3>
  IO130  = P3E_CPU0_PE1_SS_R_RXN<3>
  IO131  = GND
  IO132  = P3E_CPU0_PE1_SS_R_RXP<3>
  IO133  = P3E_CPU0_PE1_SS_C_TXN<2>
  IO134  = GND
  IO135  = P3E_CPU0_PE1_SS_C_TXP<2>
  IO136  = P3E_CPU0_PE1_SS_R_RXN<2>
  IO137  = GND
  IO138  = P3E_CPU0_PE1_SS_R_RXP<2>
  IO139  = P3E_CPU0_PE1_SS_C_TXN<1>
  IO140  = GND
  IO141  = P3E_CPU0_PE1_SS_C_TXP<1>
  IO142  = P3E_CPU0_PE1_SS_R_RXN<1>
  IO143  = GND
  IO144  = P3E_CPU0_PE1_SS_R_RXP<1>
  IO145  = P3E_CPU0_PE1_SS_C_TXN<0>
  IO146  = GND
  IO147  = P3E_CPU0_PE1_SS_C_TXP<0>
  IO148  = P3E_CPU0_PE1_SS_R_RXN<0>
  IO149  = GND
  IO150  = P3E_CPU0_PE1_SS_R_RXP<0>
  IO151  = P3E_CPU0_PE2_SS_C_TXN<0>
  IO152  = GND
  IO153  = P3E_CPU0_PE2_SS_C_TXP<0>
  IO154  = P3E_CPU0_PE2_SS_RXN<0>
  IO155  = GND
  IO156  = P3E_CPU0_PE2_SS_RXP<0>
  IO157  = P3E_CPU0_PE2_SS_C_TXP<1>
  IO158  = GND
  IO159  = P3E_CPU0_PE2_SS_C_TXN<1>
  IO160  = P3E_CPU0_PE2_SS_RXN<1>
  IO161  = GND
  IO162  = P3E_CPU0_PE2_SS_RXP<1>
  IO163  = P3E_CPU0_PE2_SS_C_TXN<2>
  IO164  = GND
  IO165  = P3E_CPU0_PE2_SS_C_TXP<2>
  IO166  = P3E_CPU0_PE2_SS_RXN<2>
  IO167  = GND
  IO168  = P3E_CPU0_PE2_SS_RXP<2>
  IO169  = P3E_CPU0_PE2_SS_C_TXN<3>
  IO170  = GND
  IO171  = P3E_CPU0_PE2_SS_C_TXP<3>
  IO172  = P3E_CPU0_PE2_SS_RXN<3>
  IO173  = GND
  IO174  = P3E_CPU0_PE2_SS_RXP<3>
  IO175  = P3E_CPU0_PE2_SS_C_TXN<4>
  IO176  = GND
  IO177  = P3E_CPU0_PE2_SS_C_TXP<4>
  IO178  = P3E_CPU0_PE2_SS_RXN<4>
  IO179  = GND
  IO180  = P3E_CPU0_PE2_SS_RXP<4>
  IO181  = P3E_CPU0_PE2_SS_C_TXN<5>
  IO182  = GND
  IO183  = P3E_CPU0_PE2_SS_C_TXP<5>
  IO184  = P3E_CPU0_PE2_SS_RXN<5>
  IO185  = GND
  IO186  = P3E_CPU0_PE2_SS_RXP<5>
  IO187  = P3E_CPU0_PE2_SS_C_TXN<6>
  IO188  = GND
  IO189  = P3E_CPU0_PE2_SS_C_TXP<6>
  IO190  = P3E_CPU0_PE2_SS_RXP<6>
  IO191  = GND
  IO192  = P3E_CPU0_PE2_SS_RXN<6>
  IO193  = P3E_CPU0_PE2_SS_C_TXN<7>
  IO194  = GND
  IO195  = P3E_CPU0_PE2_SS_C_TXP<7>
  IO196  = P3E_CPU0_PE2_SS_RXN<7>
  IO197  = GND
  IO198  = P3E_CPU0_PE2_SS_RXP<7>
  IO199  = FM_PRSNT_2_6_N
  IO200  = GND
  MH1  = GND
  MH2  = GND

(kicad_pcb
	(version 20260206)
	(generator "pcbnew")
	(generator_version "10.0")
	(general
		(thickness 1.6)
		(legacy_teardrops no)
	)
	(paper "A4")
	(title_block
		(title "Wiwynn_Tioga_Pass_MB.brd")
		(comment 1 "Tioga Pass / footprint 949 of 4770 (J8G1), pads 94-139 of 204")
	)
	(layers
		(0 "F.Cu" signal "TOP")
		(4 "In1.Cu" signal "L2GND")
		(6 "In2.Cu" signal "L3")
		(8 "In3.Cu" signal "L4GND")
		(10 "In4.Cu" signal "L5")
		(12 "In5.Cu" signal "L6GND")
		(14 "In6.Cu" signal "L7VCC")
		(16 "In7.Cu" signal "L8VCC")
		(18 "In8.Cu" signal "L9GND")
		(20 "In9.Cu" signal "L10")
		(22 "In10.Cu" signal "L11GND")
		(24 "In11.Cu" signal "L12")
		(26 "In12.Cu" signal "L13GND")
		(2 "B.Cu" signal "BOTTOM")
		(9 "F.Adhes" user "F.Adhesive")
		(11 "B.Adhes" user "B.Adhesive")
		(13 "F.Paste" user "Package Geometry/Pastemask Top")
		(15 "B.Paste" user "Package Geometry/Pastemask Bottom")
		(5 "F.SilkS" user "Ref Des/Silkscreen Top")
		(7 "B.SilkS" user "Ref Des/Silkscreen Bottom")
		(1 "F.Mask" user "Board Geometry/Soldermask Top")
		(3 "B.Mask" user "Board Geometry/Soldermask Bottom")
		(17 "Dwgs.User" user "User.Drawings")
		(19 "Cmts.User" user "User.Comments")
		(21 "Eco1.User" user "User.Eco1")
		(23 "Eco2.User" user "User.Eco2")
		(25 "Edge.Cuts" user "Board Geometry/Outline")
		(27 "Margin" user)
		(31 "F.CrtYd" user "Package Geometry/Place Bound Top")
		(29 "B.CrtYd" user "Package Geometry/Place Bound Bottom")
		(35 "F.Fab" user "Ref Des/Assembly Top")
		(33 "B.Fab" user "Ref Des/Assembly Bottom")
	)
	(footprint ""
		(layer "F.Cu")
		(at 474.080078 -7.789672 -90)
		(property "Reference" "J8G1"
			(at -3.126486 25.39111 0)
			(unlocked yes)
			(layer "F.SilkS")
			(effects
				(font
					(size 0.7874 0.5842)
					(thickness 0.1524)
				)
				(justify left)
			)
		)
		(property "Value" ""
			(at 0 0 270)
			(layer "F.Fab")
			(effects
				(font
					(size 1.27 1.27)
				)
			)
		)
		(duplicate_pad_numbers_are_jumpers no)
		(pad "92" smd rect
			(at 3.4036 39.204392 270)
			(size 1.1938 0.508)
			(layers "F.Cu" "F.Mask" "F.Paste")
			(net "GND")
		)
		(pad "93" smd rect
			(at 0 40.004492 270)
			(size 1.1938 0.508)
			(layers "F.Cu" "F.Mask" "F.Paste")
			(net "P3E_CPU0_PE1_PCH_CON_TXP<9>")
		)
		(pad "94" smd rect
			(at 3.4036 40.004492 270)
			(size 1.1938 0.508)
			(layers "F.Cu" "F.Mask" "F.Paste")
			(net "P3E_CPU0_PE1_PCH_CON_RXN<9>")
		)
		(pad "95" smd rect
			(at 0 40.804592 270)
			(size 1.1938 0.508)
			(layers "F.Cu" "F.Mask" "F.Paste")
			(net "GND")
		)
		(pad "96" smd rect
			(at 3.4036 40.804592 270)
			(size 1.1938 0.508)
			(layers "F.Cu" "F.Mask" "F.Paste")
			(net "P3E_CPU0_PE1_PCH_CON_RXP<9>")
		)
		(pad "97" smd rect
			(at 0 41.604692 270)
			(size 1.1938 0.508)
			(layers "F.Cu" "F.Mask" "F.Paste")
			(net "P3E_CPU0_PE1_PCH_CON_TXN<8>")
		)
		(pad "98" smd rect
			(at 3.4036 41.604692 270)
			(size 1.1938 0.508)
			(layers "F.Cu" "F.Mask" "F.Paste")
			(net "GND")
		)
		(pad "99" smd rect
			(at 0 42.404792 270)
			(size 1.1938 0.508)
			(layers "F.Cu" "F.Mask" "F.Paste")
			(net "P3E_CPU0_PE1_PCH_CON_TXP<8>")
		)
		(pad "100" smd rect
			(at 3.4036 42.404792 270)
			(size 1.1938 0.508)
			(layers "F.Cu" "F.Mask" "F.Paste")
			(net "P3E_CPU0_PE1_PCH_CON_RXN<8>")
		)
		(pad "101" smd rect
			(at 0 43.204892 270)
			(size 1.1938 0.508)
			(layers "F.Cu" "F.Mask" "F.Paste")
			(net "GND")
		)
		(pad "102" smd rect
			(at 3.4036 43.204892 270)
			(size 1.1938 0.508)
			(layers "F.Cu" "F.Mask" "F.Paste")
			(net "P3E_CPU0_PE1_PCH_CON_RXP<8>")
		)
		(pad "103" smd rect
			(at 0 44.004992 270)
			(size 1.1938 0.508)
			(layers "F.Cu" "F.Mask" "F.Paste")
			(net "P3E_CPU0_PE1_SS_C_TXP<7>")
		)
		(pad "104" smd rect
			(at 3.4036 44.004992 270)
			(size 1.1938 0.508)
			(layers "F.Cu" "F.Mask" "F.Paste")
			(net "GND")
		)
		(pad "105" smd rect
			(at 0 44.805092 270)
			(size 1.1938 0.508)
			(layers "F.Cu" "F.Mask" "F.Paste")
			(net "P3E_CPU0_PE1_SS_C_TXN<7>")
		)
		(pad "106" smd rect
			(at 3.4036 44.805092 270)
			(size 1.1938 0.508)
			(layers "F.Cu" "F.Mask" "F.Paste")
			(net "P3E_CPU0_PE1_SS_R_RXN<7>")
		)
		(pad "107" smd rect
			(at 0 45.605192 270)
			(size 1.1938 0.508)
			(layers "F.Cu" "F.Mask" "F.Paste")
			(net "GND")
		)
		(pad "108" smd rect
			(at 3.4036 45.605192 270)
			(size 1.1938 0.508)
			(layers "F.Cu" "F.Mask" "F.Paste")
			(net "P3E_CPU0_PE1_SS_R_RXP<7>")
		)
		(pad "109" smd rect
			(at 0 46.405292 270)
			(size 1.1938 0.508)
			(layers "F.Cu" "F.Mask" "F.Paste")
			(net "P3E_CPU0_PE1_SS_C_TXN<6>")
		)
		(pad "110" smd rect
			(at 3.4036 46.405292 270)
			(size 1.1938 0.508)
			(layers "F.Cu" "F.Mask" "F.Paste")
			(net "GND")
		)
		(pad "111" smd rect
			(at 0 47.205392 270)
			(size 1.1938 0.508)
			(layers "F.Cu" "F.Mask" "F.Paste")
			(net "P3E_CPU0_PE1_SS_C_TXP<6>")
		)
		(pad "112" smd rect
			(at 3.4036 47.205392 270)
			(size 1.1938 0.508)
			(layers "F.Cu" "F.Mask" "F.Paste")
			(net "P3E_CPU0_PE1_SS_R_RXN<6>")
		)
		(pad "113" smd rect
			(at 0 48.005492 270)
			(size 1.1938 0.508)
			(layers "F.Cu" "F.Mask" "F.Paste")
			(net "GND")
		)
		(pad "114" smd rect
			(at 3.4036 48.005492 270)
			(size 1.1938 0.508)
			(layers "F.Cu" "F.Mask" "F.Paste")
			(net "P3E_CPU0_PE1_SS_R_RXP<6>")
		)
		(pad "115" smd rect
			(at 0 48.805592 270)
			(size 1.1938 0.508)
			(layers "F.Cu" "F.Mask" "F.Paste")
			(net "P3E_CPU0_PE1_SS_C_TXN<5>")
		)
		(pad "116" smd rect
			(at 3.4036 48.805592 270)
			(size 1.1938 0.508)
			(layers "F.Cu" "F.Mask" "F.Paste")
			(net "GND")
		)
		(pad "117" smd rect
			(at 0 49.605692 270)
			(size 1.1938 0.508)
			(layers "F.Cu" "F.Mask" "F.Paste")
			(net "P3E_CPU0_PE1_SS_C_TXP<5>")
		)
		(pad "118" smd rect
			(at 3.4036 49.605692 270)
			(size 1.1938 0.508)
			(layers "F.Cu" "F.Mask" "F.Paste")
			(net "P3E_CPU0_PE1_SS_R_RXN<5>")
		)
		(pad "119" smd rect
			(at 0 50.405792 270)
			(size 1.1938 0.508)
			(layers "F.Cu" "F.Mask" "F.Paste")
			(net "GND")
		)
		(pad "120" smd rect
			(at 3.4036 50.405792 270)
			(size 1.1938 0.508)
			(layers "F.Cu" "F.Mask" "F.Paste")
			(net "P3E_CPU0_PE1_SS_R_RXP<5>")
		)
		(pad "121" smd rect
			(at 0 51.205892 270)
			(size 1.1938 0.508)
			(layers "F.Cu" "F.Mask" "F.Paste")
			(net "P3E_CPU0_PE1_SS_C_TXN<4>")
		)
		(pad "122" smd rect
			(at 3.4036 51.205892 270)
			(size 1.1938 0.508)
			(layers "F.Cu" "F.Mask" "F.Paste")
			(net "GND")
		)
		(pad "123" smd rect
			(at 0 52.005992 270)
			(size 1.1938 0.508)
			(layers "F.Cu" "F.Mask" "F.Paste")
			(net "P3E_CPU0_PE1_SS_C_TXP<4>")
		)
		(pad "124" smd rect
			(at 3.4036 52.005992 270)
			(size 1.1938 0.508)
			(layers "F.Cu" "F.Mask" "F.Paste")
			(net "P3E_CPU0_PE1_SS_R_RXN<4>")
		)
		(pad "125" smd rect
			(at 0 52.806092 270)
			(size 1.1938 0.508)
			(layers "F.Cu" "F.Mask" "F.Paste")
			(net "GND")
		)
		(pad "126" smd rect
			(at 3.4036 52.806092 270)
			(size 1.1938 0.508)
			(layers "F.Cu" "F.Mask" "F.Paste")
			(net "P3E_CPU0_PE1_SS_R_RXP<4>")
		)
		(pad "127" smd rect
			(at 0 53.606192 270)
			(size 1.1938 0.508)
			(layers "F.Cu" "F.Mask" "F.Paste")
			(net "P3E_CPU0_PE1_SS_C_TXN<3>")
		)
		(pad "128" smd rect
			(at 3.4036 53.606192 270)
			(size 1.1938 0.508)
			(layers "F.Cu" "F.Mask" "F.Paste")
			(net "GND")
		)
		(pad "129" smd rect
			(at 0 54.406292 270)
			(size 1.1938 0.508)
			(layers "F.Cu" "F.Mask" "F.Paste")
			(net "P3E_CPU0_PE1_SS_C_TXP<3>")
		)
		(pad "130" smd rect
			(at 3.4036 54.406292 270)
			(size 1.1938 0.508)
			(layers "F.Cu" "F.Mask" "F.Paste")
			(net "P3E_CPU0_PE1_SS_R_RXN<3>")
		)
		(pad "131" smd rect
			(at 0 55.206392 270)
			(size 1.1938 0.508)
			(layers "F.Cu" "F.Mask" "F.Paste")
			(net "GND")
		)
		(pad "132" smd rect
			(at 3.4036 55.206392 270)
			(size 1.1938 0.508)
			(layers "F.Cu" "F.Mask" "F.Paste")
			(net "P3E_CPU0_PE1_SS_R_RXP<3>")
		)
		(pad "133" smd rect
			(at 0 56.006492 270)
			(size 1.1938 0.508)
			(layers "F.Cu" "F.Mask" "F.Paste")
			(net "P3E_CPU0_PE1_SS_C_TXN<2>")
		)
		(pad "134" smd rect
			(at 3.4036 56.006492 270)
			(size 1.1938 0.508)
			(layers "F.Cu" "F.Mask" "F.Paste")
			(net "GND")
		)
		(pad "135" smd rect
			(at 0 56.806592 270)
			(size 1.1938 0.508)
			(layers "F.Cu" "F.Mask" "F.Paste")
			(net "P3E_CPU0_PE1_SS_C_TXP<2>")
		)
		(pad "136" smd rect
			(at 3.4036 56.806592 270)
			(size 1.1938 0.508)
			(layers "F.Cu" "F.Mask" "F.Paste")
			(net "P3E_CPU0_PE1_SS_R_RXN<2>")
		)
		(pad "137" smd rect
			(at 0 57.606692 270)
			(size 1.1938 0.508)
			(layers "F.Cu" "F.Mask" "F.Paste")
			(net "GND")
		)
	)
)
